(kicad_pcb
	(version 20260206)
	(generator "pcbnew")
	(generator_version "10.0")
	(general
		(thickness 1.6)
		(legacy_teardrops no)
	)
	(paper "A4")
	(title_block
		(title "Wiwynn_Tioga_Pass_MB.brd")
		(comment 1 "Tioga Pass / footprint 2254 of 4770 (U5D1), pads 3485-3597 of 3647")
	)
	(layers
		(0 "F.Cu" signal "TOP")
		(4 "In1.Cu" signal "L2GND")
		(6 "In2.Cu" signal "L3")
		(8 "In3.Cu" signal "L4GND")
		(10 "In4.Cu" signal "L5")
		(12 "In5.Cu" signal "L6GND")
		(14 "In6.Cu" signal "L7VCC")
		(16 "In7.Cu" signal "L8VCC")
		(18 "In8.Cu" signal "L9GND")
		(20 "In9.Cu" signal "L10")
		(22 "In10.Cu" signal "L11GND")
		(24 "In11.Cu" signal "L12")
		(26 "In12.Cu" signal "L13GND")
		(2 "B.Cu" signal "BOTTOM")
		(9 "F.Adhes" user "F.Adhesive")
		(11 "B.Adhes" user "B.Adhesive")
		(13 "F.Paste" user "Package Geometry/Pastemask Top")
		(15 "B.Paste" user "Package Geometry/Pastemask Bottom")
		(5 "F.SilkS" user "Ref Des/Silkscreen Top")
		(7 "B.SilkS" user "Ref Des/Silkscreen Bottom")
		(1 "F.Mask" user "Board Geometry/Soldermask Top")
		(3 "B.Mask" user "Board Geometry/Soldermask Bottom")
		(17 "Dwgs.User" user "User.Drawings")
		(19 "Cmts.User" user "User.Comments")
		(21 "Eco1.User" user "User.Eco1")
		(23 "Eco2.User" user "User.Eco2")
		(25 "Edge.Cuts" user "Board Geometry/Outline")
		(27 "Margin" user)
		(31 "F.CrtYd" user "Package Geometry/Place Bound Top")
		(29 "B.CrtYd" user "Package Geometry/Place Bound Bottom")
		(35 "F.Fab" user "Ref Des/Assembly Top")
		(33 "B.Fab" user "Ref Des/Assembly Bottom")
	)
	(footprint ""
		(layer "F.Cu")
		(at 270.000222 -76.550012 180)
		(property "Reference" "U5D1"
			(at 19.124422 31.601918 0)
			(unlocked yes)
			(layer "F.SilkS")
			(effects
				(font
					(size 0.7874 0.5842)
					(thickness 0.1524)
				)
			)
		)
		(property "Value" ""
			(at 0 0 180)
			(layer "F.Fab")
			(effects
				(font
					(size 1.27 1.27)
				)
			)
		)
		(duplicate_pad_numbers_are_jumpers no)
		(pad "U16" smd circle
			(at -24.373078 -17.178528)
			(size 0.4318 0.4318)
			(layers "F.Cu" "F.Mask" "F.Paste")
			(net "UPI_CPU1_CPU0_P1P1_DN<7>")
		)
		(pad "U18" smd circle
			(at -22.656038 -17.178528)
			(size 0.4318 0.4318)
			(layers "F.Cu" "F.Mask" "F.Paste")
			(net "UPI_CPU1_CPU0_P1P1_DN<4>")
		)
		(pad "U20" smd circle
			(at -20.938998 -17.178528)
			(size 0.4318 0.4318)
			(layers "F.Cu" "F.Mask" "F.Paste")
			(net "GND")
		)
		(pad "U22" smd circle
			(at -19.221958 -17.178528)
			(size 0.4318 0.4318)
			(layers "F.Cu" "F.Mask" "F.Paste")
			(net "GND")
		)
		(pad "U24" smd circle
			(at -17.504918 -17.178528)
			(size 0.4318 0.4318)
			(layers "F.Cu" "F.Mask" "F.Paste")
			(net "GND")
		)
		(pad "U26" smd circle
			(at -15.787878 -17.178528)
			(size 0.4318 0.4318)
			(layers "F.Cu" "F.Mask" "F.Paste")
			(net "M_B_DQ<62>")
		)
		(pad "U28" smd circle
			(at -14.071092 -17.178528)
			(size 0.4318 0.4318)
			(layers "F.Cu" "F.Mask" "F.Paste")
			(net "M_B_DQ<56>")
		)
		(pad "U30" smd circle
			(at -12.354052 -17.178528)
			(size 0.4318 0.4318)
			(layers "F.Cu" "F.Mask" "F.Paste")
			(net "GND")
		)
		(pad "U32" smd circle
			(at -10.637012 -17.178528)
			(size 0.4318 0.4318)
			(layers "F.Cu" "F.Mask" "F.Paste")
			(net "M_C_DQ<46>")
		)
		(pad "U34" smd circle
			(at -8.919972 -17.178528)
			(size 0.4318 0.4318)
			(layers "F.Cu" "F.Mask" "F.Paste")
			(net "M_C_DQ<40>")
		)
		(pad "U36" smd circle
			(at -7.202932 -17.178528)
			(size 0.4318 0.4318)
			(layers "F.Cu" "F.Mask" "F.Paste")
			(net "GND")
		)
		(pad "U38" smd circle
			(at -5.485892 -17.178528)
			(size 0.4318 0.4318)
			(layers "F.Cu" "F.Mask" "F.Paste")
			(net "M_C_DQ<38>")
		)
		(pad "U40" smd circle
			(at -3.769106 -17.178528)
			(size 0.4318 0.4318)
			(layers "F.Cu" "F.Mask" "F.Paste")
			(net "M_C_DQ<32>")
		)
		(pad "U42" smd circle
			(at -2.052066 -17.178528)
			(size 0.4318 0.4318)
			(layers "F.Cu" "F.Mask" "F.Paste")
			(net "GND")
		)
		(pad "U46" smd circle
			(at 2.910586 -18.978372)
			(size 0.4318 0.4318)
			(layers "F.Cu" "F.Mask" "F.Paste")
			(net "PVDDQ_ABC")
		)
		(pad "U48" smd circle
			(at 4.627626 -18.978372)
			(size 0.4318 0.4318)
			(layers "F.Cu" "F.Mask" "F.Paste")
			(net "PVDDQ_ABC")
		)
		(pad "U50" smd circle
			(at 6.344412 -18.978372)
			(size 0.4318 0.4318)
			(layers "F.Cu" "F.Mask" "F.Paste")
			(net "PVDDQ_ABC")
		)
		(pad "U52" smd circle
			(at 8.061452 -18.978372)
			(size 0.4318 0.4318)
			(layers "F.Cu" "F.Mask" "F.Paste")
			(net "PVDDQ_ABC")
		)
		(pad "U54" smd circle
			(at 9.778492 -18.978372)
			(size 0.4318 0.4318)
			(layers "F.Cu" "F.Mask" "F.Paste")
			(net "PVDDQ_ABC")
		)
		(pad "U56" smd circle
			(at 11.495532 -18.978372)
			(size 0.4318 0.4318)
			(layers "F.Cu" "F.Mask" "F.Paste")
			(net "PVDDQ_ABC")
		)
		(pad "U58" smd circle
			(at 13.212572 -18.978372)
			(size 0.4318 0.4318)
			(layers "F.Cu" "F.Mask" "F.Paste")
			(net "PVDDQ_ABC")
		)
		(pad "U60" smd circle
			(at 14.929612 -18.978372)
			(size 0.4318 0.4318)
			(layers "F.Cu" "F.Mask" "F.Paste")
			(net "PVDDQ_ABC")
		)
		(pad "U62" smd circle
			(at 16.646398 -18.978372)
			(size 0.4318 0.4318)
			(layers "F.Cu" "F.Mask" "F.Paste")
			(net "PVDDQ_ABC")
		)
		(pad "U64" smd circle
			(at 18.363438 -18.978372)
			(size 0.4318 0.4318)
			(layers "F.Cu" "F.Mask" "F.Paste")
			(net "M_ABC_RST_N")
		)
		(pad "U66" smd circle
			(at 20.080478 -18.978372)
			(size 0.4318 0.4318)
			(layers "F.Cu" "F.Mask" "F.Paste")
			(net "TP_CPU0_RSVD_261")
		)
		(pad "U68" smd circle
			(at 21.797518 -18.978372)
			(size 0.4318 0.4318)
			(layers "F.Cu" "F.Mask" "F.Paste")
			(net "GND")
		)
		(pad "U70" smd circle
			(at 23.514558 -18.978372)
			(size 0.4318 0.4318)
			(layers "F.Cu" "F.Mask" "F.Paste")
			(net "GND")
		)
		(pad "U72" smd circle
			(at 25.231598 -18.978372)
			(size 0.4318 0.4318)
			(layers "F.Cu" "F.Mask" "F.Paste")
			(net "M_C_DQS_DN<11>")
		)
		(pad "U74" smd circle
			(at 26.948384 -18.978372)
			(size 0.4318 0.4318)
			(layers "F.Cu" "F.Mask" "F.Paste")
			(net "GND")
		)
		(pad "U76" smd circle
			(at 28.665424 -18.978372)
			(size 0.4318 0.4318)
			(layers "F.Cu" "F.Mask" "F.Paste")
			(net "GND")
		)
		(pad "U78" smd circle
			(at 30.382464 -18.978372)
			(size 0.4318 0.4318)
			(layers "F.Cu" "F.Mask" "F.Paste")
			(net "GND")
		)
		(pad "U80" smd circle
			(at 32.099504 -18.978372)
			(size 0.4318 0.4318)
			(layers "F.Cu" "F.Mask" "F.Paste")
			(net "GND")
		)
		(pad "U82" smd circle
			(at 33.816544 -18.978372)
			(size 0.4318 0.4318)
			(layers "F.Cu" "F.Mask" "F.Paste")
			(net "M_A_DQS_DN<11>")
		)
		(pad "U84" smd circle
			(at 35.533584 -18.978372)
			(size 0.4318 0.4318)
			(layers "F.Cu" "F.Mask" "F.Paste")
			(net "M_A_DQS_DN<10>")
		)
		(pad "U86" smd custom
			(at 37.250624 -18.978372 270)
			(size 0.10795 0.10795)
			(layers "F.Cu" "F.Mask" "F.Paste")
			(net "GND")
			(options
				(clearance outline)
				(anchor circle)
			)
			(primitives
				(gr_poly
					(pts
						(arc
							(start 0.2159 -0.0381)
							(mid 0 -0.254)
							(end -0.2159 -0.0381)
						)
						(arc
							(start -0.2159 0.0381)
							(mid 0 0.254)
							(end 0.2159 0.0381)
						)
					)
					(width 0)
					(fill yes)
				)
			)
		)
		(pad "V1" smd custom
			(at -37.250624 -16.683228 90)
			(size 0.10795 0.10795)
			(layers "F.Cu" "F.Mask" "F.Paste")
			(net "GND")
			(options
				(clearance outline)
				(anchor circle)
			)
			(primitives
				(gr_poly
					(pts
						(arc
							(start 0.2159 -0.0381)
							(mid 0 -0.254)
							(end -0.2159 -0.0381)
						)
						(arc
							(start -0.2159 0.0381)
							(mid 0 0.254)
							(end 0.2159 0.0381)
						)
					)
					(width 0)
					(fill yes)
				)
			)
		)
		(pad "V3" smd circle
			(at -35.533584 -16.683228)
			(size 0.4318 0.4318)
			(layers "F.Cu" "F.Mask" "F.Paste")
			(net "UPI_CPU0_CPU1_P0P0_DN<17>")
		)
		(pad "V5" smd circle
			(at -33.816544 -16.683228)
			(size 0.4318 0.4318)
			(layers "F.Cu" "F.Mask" "F.Paste")
			(net "GND")
		)
		(pad "V7" smd circle
			(at -32.099504 -16.683228)
			(size 0.4318 0.4318)
			(layers "F.Cu" "F.Mask" "F.Paste")
			(net "UPI_CPU1_CPU0_P1P1_DN<17>")
		)
		(pad "V9" smd circle
			(at -30.382464 -16.683228)
			(size 0.4318 0.4318)
			(layers "F.Cu" "F.Mask" "F.Paste")
			(net "GND")
		)
		(pad "V11" smd circle
			(at -28.665424 -16.683228)
			(size 0.4318 0.4318)
			(layers "F.Cu" "F.Mask" "F.Paste")
			(net "GND")
		)
		(pad "V13" smd circle
			(at -26.948384 -16.683228)
			(size 0.4318 0.4318)
			(layers "F.Cu" "F.Mask" "F.Paste")
			(net "GND")
		)
		(pad "V15" smd circle
			(at -25.231598 -16.683228)
			(size 0.4318 0.4318)
			(layers "F.Cu" "F.Mask" "F.Paste")
			(net "GND")
		)
		(pad "V17" smd circle
			(at -23.514558 -16.683228)
			(size 0.4318 0.4318)
			(layers "F.Cu" "F.Mask" "F.Paste")
			(net "UPI_CPU1_CPU0_P1P1_DP<6>")
		)
		(pad "V19" smd circle
			(at -21.797518 -16.683228)
			(size 0.4318 0.4318)
			(layers "F.Cu" "F.Mask" "F.Paste")
			(net "UPI_CPU1_CPU0_P1P1_DN<2>")
		)
		(pad "V21" smd circle
			(at -20.080478 -16.683228)
			(size 0.4318 0.4318)
			(layers "F.Cu" "F.Mask" "F.Paste")
			(net "GND")
		)
		(pad "V23" smd circle
			(at -18.363438 -16.683228)
			(size 0.4318 0.4318)
			(layers "F.Cu" "F.Mask" "F.Paste")
			(net "GND")
		)
		(pad "V25" smd circle
			(at -16.646398 -16.683228)
			(size 0.4318 0.4318)
			(layers "F.Cu" "F.Mask" "F.Paste")
			(net "M_B_DQ<58>")
		)
		(pad "V27" smd circle
			(at -14.929612 -16.683228)
			(size 0.4318 0.4318)
			(layers "F.Cu" "F.Mask" "F.Paste")
			(net "M_B_DQS_DP<16>")
		)
		(pad "V29" smd circle
			(at -13.212572 -16.683228)
			(size 0.4318 0.4318)
			(layers "F.Cu" "F.Mask" "F.Paste")
			(net "M_B_DQ<60>")
		)
		(pad "V31" smd circle
			(at -11.495532 -16.683228)
			(size 0.4318 0.4318)
			(layers "F.Cu" "F.Mask" "F.Paste")
			(net "M_C_DQ<42>")
		)
		(pad "V33" smd circle
			(at -9.778492 -16.683228)
			(size 0.4318 0.4318)
			(layers "F.Cu" "F.Mask" "F.Paste")
			(net "M_C_DQS_DP<14>")
		)
		(pad "V35" smd circle
			(at -8.061452 -16.683228)
			(size 0.4318 0.4318)
			(layers "F.Cu" "F.Mask" "F.Paste")
			(net "M_C_DQ<44>")
		)
		(pad "V37" smd circle
			(at -6.344412 -16.683228)
			(size 0.4318 0.4318)
			(layers "F.Cu" "F.Mask" "F.Paste")
			(net "M_C_DQ<34>")
		)
		(pad "V39" smd circle
			(at -4.627626 -16.683228)
			(size 0.4318 0.4318)
			(layers "F.Cu" "F.Mask" "F.Paste")
			(net "M_C_DQS_DP<13>")
		)
		(pad "V41" smd circle
			(at -2.910586 -16.683228)
			(size 0.4318 0.4318)
			(layers "F.Cu" "F.Mask" "F.Paste")
			(net "M_C_DQ<36>")
		)
		(pad "V43" smd circle
			(at -1.193546 -16.683228)
			(size 0.4318 0.4318)
			(layers "F.Cu" "F.Mask" "F.Paste")
			(net "GND")
		)
		(pad "V45" smd circle
			(at 2.052066 -18.483072)
			(size 0.508 0.508)
			(layers "F.Cu" "F.Mask" "F.Paste")
			(net "M_C_CS_N<7>")
		)
		(pad "V47" smd circle
			(at 3.769106 -18.483072)
			(size 0.4318 0.4318)
			(layers "F.Cu" "F.Mask" "F.Paste")
			(net "M_B_CS_N<3>")
		)
		(pad "V49" smd circle
			(at 5.485892 -18.483072)
			(size 0.4318 0.4318)
			(layers "F.Cu" "F.Mask" "F.Paste")
			(net "M_C_ODT<2>")
		)
		(pad "V51" smd circle
			(at 7.202932 -18.483072)
			(size 0.4318 0.4318)
			(layers "F.Cu" "F.Mask" "F.Paste")
			(net "M_C_CS_N<0>")
		)
		(pad "V53" smd circle
			(at 8.919972 -18.483072)
			(size 0.4318 0.4318)
			(layers "F.Cu" "F.Mask" "F.Paste")
			(net "M_C_PAR")
		)
		(pad "V55" smd circle
			(at 10.637012 -18.483072)
			(size 0.4318 0.4318)
			(layers "F.Cu" "F.Mask" "F.Paste")
			(net "M_C_CLK_DP<1>")
		)
		(pad "V57" smd circle
			(at 12.354052 -18.483072)
			(size 0.4318 0.4318)
			(layers "F.Cu" "F.Mask" "F.Paste")
			(net "M_C_CLK_DP<3>")
		)
		(pad "V59" smd circle
			(at 14.071092 -18.483072)
			(size 0.4318 0.4318)
			(layers "F.Cu" "F.Mask" "F.Paste")
			(net "M_C_MA<5>")
		)
		(pad "V61" smd circle
			(at 15.787878 -18.483072)
			(size 0.4318 0.4318)
			(layers "F.Cu" "F.Mask" "F.Paste")
			(net "M_B_MA<7>")
		)
		(pad "V63" smd circle
			(at 17.504918 -18.483072)
			(size 0.4318 0.4318)
			(layers "F.Cu" "F.Mask" "F.Paste")
			(net "M_C_CKE<2>")
		)
		(pad "V65" smd circle
			(at 19.221958 -18.483072)
			(size 0.4318 0.4318)
			(layers "F.Cu" "F.Mask" "F.Paste")
			(net "TP_CPU0_RSVD_260")
		)
		(pad "V67" smd circle
			(at 20.938998 -18.483072)
			(size 0.4318 0.4318)
			(layers "F.Cu" "F.Mask" "F.Paste")
			(net "TP_CPU0_RSVD_259")
		)
		(pad "V69" smd circle
			(at 22.656038 -18.483072)
			(size 0.4318 0.4318)
			(layers "F.Cu" "F.Mask" "F.Paste")
			(net "M_C_DQ<23>")
		)
		(pad "V71" smd circle
			(at 24.373078 -18.483072)
			(size 0.4318 0.4318)
			(layers "F.Cu" "F.Mask" "F.Paste")
			(net "M_C_DQS_DP<11>")
		)
		(pad "V73" smd circle
			(at 26.090118 -18.483072)
			(size 0.4318 0.4318)
			(layers "F.Cu" "F.Mask" "F.Paste")
			(net "GND")
		)
		(pad "V75" smd circle
			(at 27.806904 -18.483072)
			(size 0.4318 0.4318)
			(layers "F.Cu" "F.Mask" "F.Paste")
			(net "GND")
		)
		(pad "V77" smd circle
			(at 29.523944 -18.483072)
			(size 0.4318 0.4318)
			(layers "F.Cu" "F.Mask" "F.Paste")
			(net "GND")
		)
		(pad "V79" smd circle
			(at 31.240984 -18.483072)
			(size 0.4318 0.4318)
			(layers "F.Cu" "F.Mask" "F.Paste")
			(net "M_A_DQ<21>")
		)
		(pad "V81" smd circle
			(at 32.958024 -18.483072)
			(size 0.4318 0.4318)
			(layers "F.Cu" "F.Mask" "F.Paste")
			(net "M_A_DQ<16>")
		)
		(pad "V83" smd circle
			(at 34.675064 -18.483072)
			(size 0.4318 0.4318)
			(layers "F.Cu" "F.Mask" "F.Paste")
			(net "GND")
		)
		(pad "V85" smd circle
			(at 36.392104 -18.483072)
			(size 0.4318 0.4318)
			(layers "F.Cu" "F.Mask" "F.Paste")
			(net "M_A_DQS_DP<10>")
		)
		(pad "W2" smd circle
			(at -36.392104 -16.187674)
			(size 0.4318 0.4318)
			(layers "F.Cu" "F.Mask" "F.Paste")
			(net "UPI_CPU0_CPU1_P0P0_DP<16>")
		)
		(pad "W4" smd circle
			(at -34.675064 -16.187674)
			(size 0.4318 0.4318)
			(layers "F.Cu" "F.Mask" "F.Paste")
			(net "PVCCIO_CPU0")
		)
		(pad "W6" smd circle
			(at -32.958024 -16.187674)
			(size 0.4318 0.4318)
			(layers "F.Cu" "F.Mask" "F.Paste")
			(net "PVCCIO_CPU0")
		)
		(pad "W8" smd circle
			(at -31.240984 -16.187674)
			(size 0.4318 0.4318)
			(layers "F.Cu" "F.Mask" "F.Paste")
			(net "GND")
		)
		(pad "W10" smd circle
			(at -29.523944 -16.187674)
			(size 0.4318 0.4318)
			(layers "F.Cu" "F.Mask" "F.Paste")
			(net "PVCCIO_CPU0")
		)
		(pad "W12" smd circle
			(at -27.806904 -16.187674)
			(size 0.4318 0.4318)
			(layers "F.Cu" "F.Mask" "F.Paste")
			(net "GND")
		)
		(pad "W14" smd circle
			(at -26.090118 -16.187674)
			(size 0.4318 0.4318)
			(layers "F.Cu" "F.Mask" "F.Paste")
			(net "XDP_CPU_TMS")
		)
		(pad "W16" smd circle
			(at -24.373078 -16.187674)
			(size 0.4318 0.4318)
			(layers "F.Cu" "F.Mask" "F.Paste")
			(net "UPI_CPU1_CPU0_P1P1_DP<7>")
		)
		(pad "W18" smd circle
			(at -22.656038 -16.187674)
			(size 0.4318 0.4318)
			(layers "F.Cu" "F.Mask" "F.Paste")
			(net "UPI_CPU1_CPU0_P1P1_DN<6>")
		)
		(pad "W20" smd circle
			(at -20.938998 -16.187674)
			(size 0.4318 0.4318)
			(layers "F.Cu" "F.Mask" "F.Paste")
			(net "UPI_CPU1_CPU0_P1P1_DP<1>")
		)
		(pad "W22" smd circle
			(at -19.221958 -16.187674)
			(size 0.4318 0.4318)
			(layers "F.Cu" "F.Mask" "F.Paste")
			(net "GND")
		)
		(pad "W24" smd circle
			(at -17.504918 -16.187674)
			(size 0.4318 0.4318)
			(layers "F.Cu" "F.Mask" "F.Paste")
			(net "GND")
		)
		(pad "W26" smd circle
			(at -15.787878 -16.187674)
			(size 0.4318 0.4318)
			(layers "F.Cu" "F.Mask" "F.Paste")
			(net "GND")
		)
		(pad "W28" smd circle
			(at -14.071092 -16.187674)
			(size 0.4318 0.4318)
			(layers "F.Cu" "F.Mask" "F.Paste")
			(net "GND")
		)
		(pad "W30" smd circle
			(at -12.354052 -16.187674)
			(size 0.4318 0.4318)
			(layers "F.Cu" "F.Mask" "F.Paste")
			(net "GND")
		)
		(pad "W32" smd circle
			(at -10.637012 -16.187674)
			(size 0.4318 0.4318)
			(layers "F.Cu" "F.Mask" "F.Paste")
			(net "GND")
		)
		(pad "W34" smd circle
			(at -8.919972 -16.187674)
			(size 0.4318 0.4318)
			(layers "F.Cu" "F.Mask" "F.Paste")
			(net "GND")
		)
		(pad "W36" smd circle
			(at -7.202932 -16.187674)
			(size 0.4318 0.4318)
			(layers "F.Cu" "F.Mask" "F.Paste")
			(net "GND")
		)
		(pad "W38" smd circle
			(at -5.485892 -16.187674)
			(size 0.4318 0.4318)
			(layers "F.Cu" "F.Mask" "F.Paste")
			(net "GND")
		)
		(pad "W40" smd circle
			(at -3.769106 -16.187674)
			(size 0.4318 0.4318)
			(layers "F.Cu" "F.Mask" "F.Paste")
			(net "GND")
		)
		(pad "W42" smd circle
			(at -2.052066 -16.187674)
			(size 0.4318 0.4318)
			(layers "F.Cu" "F.Mask" "F.Paste")
			(net "GND")
		)
		(pad "W46" smd circle
			(at 2.910586 -17.988026)
			(size 0.4318 0.4318)
			(layers "F.Cu" "F.Mask" "F.Paste")
			(net "M_C_CS_N<2>")
		)
		(pad "W48" smd circle
			(at 4.627626 -17.988026)
			(size 0.4318 0.4318)
			(layers "F.Cu" "F.Mask" "F.Paste")
			(net "M_C_CS_N<5>")
		)
		(pad "W50" smd circle
			(at 6.344412 -17.988026)
			(size 0.4318 0.4318)
			(layers "F.Cu" "F.Mask" "F.Paste")
			(net "M_C_MA<14>")
		)
		(pad "W52" smd circle
			(at 8.061452 -17.988026)
			(size 0.4318 0.4318)
			(layers "F.Cu" "F.Mask" "F.Paste")
			(net "M_C_BA<0>")
		)
		(pad "W54" smd circle
			(at 9.778492 -17.988026)
			(size 0.4318 0.4318)
			(layers "F.Cu" "F.Mask" "F.Paste")
			(net "M_C_CLK_DN<1>")
		)
		(pad "W56" smd circle
			(at 11.495532 -17.988026)
			(size 0.4318 0.4318)
			(layers "F.Cu" "F.Mask" "F.Paste")
			(net "M_C_CLK_DN<3>")
		)
		(pad "W58" smd circle
			(at 13.212572 -17.988026)
			(size 0.4318 0.4318)
			(layers "F.Cu" "F.Mask" "F.Paste")
			(net "M_C_MA<3>")
		)
		(pad "W60" smd circle
			(at 14.929612 -17.988026)
			(size 0.4318 0.4318)
			(layers "F.Cu" "F.Mask" "F.Paste")
			(net "M_B_MA<8>")
		)
		(pad "W62" smd circle
			(at 16.646398 -17.988026)
			(size 0.4318 0.4318)
			(layers "F.Cu" "F.Mask" "F.Paste")
			(net "M_B_ALERT_N")
		)
		(pad "W64" smd circle
			(at 18.363438 -17.988026)
			(size 0.4318 0.4318)
			(layers "F.Cu" "F.Mask" "F.Paste")
			(net "PVDDQ_ABC")
		)
		(pad "W66" smd circle
			(at 20.080478 -17.988026)
			(size 0.4318 0.4318)
			(layers "F.Cu" "F.Mask" "F.Paste")
			(net "TP_CPU0_RSVD_258")
		)
		(pad "W68" smd circle
			(at 21.797518 -17.988026)
			(size 0.4318 0.4318)
			(layers "F.Cu" "F.Mask" "F.Paste")
			(net "GND")
		)
		(pad "W70" smd circle
			(at 23.514558 -17.988026)
			(size 0.4318 0.4318)
			(layers "F.Cu" "F.Mask" "F.Paste")
			(net "M_C_DQS_DP<2>")
		)
		(pad "W72" smd circle
			(at 25.231598 -17.988026)
			(size 0.4318 0.4318)
			(layers "F.Cu" "F.Mask" "F.Paste")
			(net "M_C_DQ<16>")
		)
	)
)
